# T6G (Grand Teton) — schematic netlist excerpt (pin names and nets, part order shuffled) for the footprints in the layout excerpt that follows; sources: Cadence DE-HDL packaged netlist, KiCad conversion of 04192023_DAF0TMB3IC0_F0TG_MB_C_brd_V02_OCP.brd

C2411  Q_CAP  22UF 4V 20% X6S  pkg C0402  page 74 : A = PVDDCR_SOC_P1 ; B = GND
R3180  Q_RES  0 5% CHIP  pkg 0402LF  page 137 : A = OCP_V3_2_PRSNTA_R_N ; B = GND

(kicad_pcb
	(version 20260206)
	(generator "pcbnew")
	(generator_version "10.0")
	(general
		(thickness 1.6)
		(legacy_teardrops no)
	)
	(paper "A4")
	(title_block
		(title "04192023_DAF0TMB3IC0_F0TG_MB_C_brd_V02_OCP.brd")
		(comment 1 "Grand Teton / footprints 6027-6028 of 8354")
	)
	(layers
		(0 "F.Cu" signal "TOP")
		(4 "In1.Cu" signal "GND")
		(6 "In2.Cu" signal "IN1")
		(8 "In3.Cu" signal "GND1")
		(10 "In4.Cu" signal "IN2")
		(12 "In5.Cu" signal "GND2")
		(14 "In6.Cu" signal "IN3")
		(16 "In7.Cu" signal "GND3")
		(18 "In8.Cu" signal "VCC")
		(20 "In9.Cu" signal "VCC1")
		(22 "In10.Cu" signal "GND4")
		(24 "In11.Cu" signal "IN4")
		(26 "In12.Cu" signal "GND5")
		(28 "In13.Cu" signal "IN5")
		(30 "In14.Cu" signal "GND6")
		(32 "In15.Cu" signal "IN6")
		(34 "In16.Cu" signal "GND7")
		(2 "B.Cu" signal "BOTTOM")
		(9 "F.Adhes" user "F.Adhesive")
		(11 "B.Adhes" user "B.Adhesive")
		(13 "F.Paste" user "Package Geometry/Pastemask Top")
		(15 "B.Paste" user "Package Geometry/Pastemask Bottom")
		(5 "F.SilkS" user "Ref Des/Silkscreen Top")
		(7 "B.SilkS" user "Ref Des/Silkscreen Bottom")
		(1 "F.Mask" user "Board Geometry/Soldermask Top")
		(3 "B.Mask" user "Board Geometry/Soldermask Bottom")
		(17 "Dwgs.User" user "User.Drawings")
		(19 "Cmts.User" user "User.Comments")
		(21 "Eco1.User" user "User.Eco1")
		(23 "Eco2.User" user "User.Eco2")
		(25 "Edge.Cuts" user "Board Geometry/Outline")
		(27 "Margin" user)
		(31 "F.CrtYd" user "Package Geometry/Place Bound Top")
		(29 "B.CrtYd" user "Package Geometry/Place Bound Bottom")
		(35 "F.Fab" user "Ref Des/Assembly Top")
		(33 "B.Fab" user "Ref Des/Assembly Bottom")
	)
	(footprint ""
		(layer "B.Cu")
		(at 104.307386 -251.781564)
		(property "Reference" "C2411"
			(at 0 0 0)
			(layer "B.SilkS")
			(hide yes)
			(effects
				(font
					(size 1.27 1.27)
				)
				(justify mirror)
			)
		)
		(property "Value" ""
			(at 0 0 0)
			(layer "B.Fab")
			(effects
				(font
					(size 1.27 1.27)
				)
				(justify mirror)
			)
		)
		(duplicate_pad_numbers_are_jumpers no)
		(fp_line
			(start -0.7874 -0.4064)
			(end -0.7874 0.4064)
			(stroke
				(width 0.1524)
				(type default)
			)
			(layer "B.SilkS")
		)
		(fp_line
			(start -0.7874 0.4064)
			(end 0.7874 0.4064)
			(stroke
				(width 0.1524)
				(type default)
			)
			(layer "B.SilkS")
		)
		(fp_line
			(start 0.7874 -0.4064)
			(end -0.7874 -0.4064)
			(stroke
				(width 0.1524)
				(type default)
			)
			(layer "B.SilkS")
		)
		(fp_line
			(start 0.7874 0.4064)
			(end 0.7874 -0.4064)
			(stroke
				(width 0.1524)
				(type default)
			)
			(layer "B.SilkS")
		)
		(fp_line
			(start -0.67945 -0.3048)
			(end -0.67945 0.3048)
			(stroke
				(width 0.1)
				(type default)
			)
			(layer "B.Fab")
		)
		(fp_line
			(start -0.67945 0.3048)
			(end -0.120396 0.3048)
			(stroke
				(width 0.1)
				(type default)
			)
			(layer "B.Fab")
		)
		(fp_line
			(start -0.12065 -0.3048)
			(end -0.67945 -0.3048)
			(stroke
				(width 0.1)
				(type default)
			)
			(layer "B.Fab")
		)
		(fp_line
			(start -0.12065 -0.2794)
			(end -0.12065 -0.3048)
			(stroke
				(width 0.1)
				(type default)
			)
			(layer "B.Fab")
		)
		(fp_line
			(start -0.120396 0.2794)
			(end 0.12065 0.2794)
			(stroke
				(width 0.1)
				(type default)
			)
			(layer "B.Fab")
		)
		(fp_line
			(start -0.120396 0.3048)
			(end -0.120396 0.2794)
			(stroke
				(width 0.1)
				(type default)
			)
			(layer "B.Fab")
		)
		(fp_line
			(start 0.12065 -0.305054)
			(end 0.12065 -0.2794)
			(stroke
				(width 0.1)
				(type default)
			)
			(layer "B.Fab")
		)
		(fp_line
			(start 0.12065 -0.2794)
			(end -0.12065 -0.2794)
			(stroke
				(width 0.1)
				(type default)
			)
			(layer "B.Fab")
		)
		(fp_line
			(start 0.12065 0.2794)
			(end 0.12065 0.3048)
			(stroke
				(width 0.1)
				(type default)
			)
			(layer "B.Fab")
		)
		(fp_line
			(start 0.12065 0.3048)
			(end 0.67945 0.3048)
			(stroke
				(width 0.1)
				(type default)
			)
			(layer "B.Fab")
		)
		(fp_line
			(start 0.67945 -0.305054)
			(end 0.12065 -0.305054)
			(stroke
				(width 0.1)
				(type default)
			)
			(layer "B.Fab")
		)
		(fp_line
			(start 0.67945 0.3048)
			(end 0.67945 -0.305054)
			(stroke
				(width 0.1)
				(type default)
			)
			(layer "B.Fab")
		)
		(pad "1" smd circle
			(at 0.40005 0 180)
			(size 0 0)
			(layers "B.Cu" "B.Mask" "B.Paste")
			(net "PVDDCR_SOC_P1")
		)
		(pad "2" smd circle
			(at -0.40005 0 180)
			(size 0 0)
			(layers "B.Cu" "B.Mask" "B.Paste")
			(net "GND")
		)
	)
	(footprint ""
		(layer "B.Cu")
		(at 60.468002 -8.319262 -90)
		(property "Reference" "R3180"
			(at 0 0 90)
			(layer "B.SilkS")
			(hide yes)
			(effects
				(font
					(size 1.27 1.27)
				)
				(justify mirror)
			)
		)
		(property "Value" ""
			(at 0 0 90)
			(layer "B.Fab")
			(effects
				(font
					(size 1.27 1.27)
				)
				(justify mirror)
			)
		)
		(duplicate_pad_numbers_are_jumpers no)
		(fp_line
			(start -0.7874 0.4064)
			(end 0.7874 0.4064)
			(stroke
				(width 0.1524)
				(type default)
			)
			(layer "B.SilkS")
		)
		(fp_line
			(start 0.7874 0.4064)
			(end 0.7874 -0.4064)
			(stroke
				(width 0.1524)
				(type default)
			)
			(layer "B.SilkS")
		)
		(fp_line
			(start -0.7874 -0.4064)
			(end -0.7874 0.4064)
			(stroke
				(width 0.1524)
				(type default)
			)
			(layer "B.SilkS")
		)
		(fp_line
			(start 0.7874 -0.4064)
			(end -0.7874 -0.4064)
			(stroke
				(width 0.1524)
				(type default)
			)
			(layer "B.SilkS")
		)
		(fp_line
			(start -0.67945 0.3048)
			(end -0.120396 0.3048)
			(stroke
				(width 0.1)
				(type default)
			)
			(layer "B.Fab")
		)
		(fp_line
			(start -0.120396 0.3048)
			(end -0.120396 0.2794)
			(stroke
				(width 0.1)
				(type default)
			)
			(layer "B.Fab")
		)
		(fp_line
			(start 0.12065 0.3048)
			(end 0.67945 0.3048)
			(stroke
				(width 0.1)
				(type default)
			)
			(layer "B.Fab")
		)
		(fp_line
			(start 0.67945 0.3048)
			(end 0.67945 -0.305054)
			(stroke
				(width 0.1)
				(type default)
			)
			(layer "B.Fab")
		)
		(fp_line
			(start -0.120396 0.2794)
			(end 0.12065 0.2794)
			(stroke
				(width 0.1)
				(type default)
			)
			(layer "B.Fab")
		)
		(fp_line
			(start 0.12065 0.2794)
			(end 0.12065 0.3048)
			(stroke
				(width 0.1)
				(type default)
			)
			(layer "B.Fab")
		)
		(fp_line
			(start -0.12065 -0.2794)
			(end -0.12065 -0.3048)
			(stroke
				(width 0.1)
				(type default)
			)
			(layer "B.Fab")
		)
		(fp_line
			(start 0.12065 -0.2794)
			(end -0.12065 -0.2794)
			(stroke
				(width 0.1)
				(type default)
			)
			(layer "B.Fab")
		)
		(fp_line
			(start -0.67945 -0.3048)
			(end -0.67945 0.3048)
			(stroke
				(width 0.1)
				(type default)
			)
			(layer "B.Fab")
		)
		(fp_line
			(start -0.12065 -0.3048)
			(end -0.67945 -0.3048)
			(stroke
				(width 0.1)
				(type default)
			)
			(layer "B.Fab")
		)
		(fp_line
			(start 0.12065 -0.305054)
			(end 0.12065 -0.2794)
			(stroke
				(width 0.1)
				(type default)
			)
			(layer "B.Fab")
		)
		(fp_line
			(start 0.67945 -0.305054)
			(end 0.12065 -0.305054)
			(stroke
				(width 0.1)
				(type default)
			)
			(layer "B.Fab")
		)
		(pad "1" smd circle
			(at 0.40005 0 90)
			(size 0 0)
			(layers "B.Cu" "B.Mask" "B.Paste")
			(net "OCP_V3_2_PRSNTA_R_N")
		)
		(pad "2" smd circle
			(at -0.40005 0 90)
			(size 0 0)
			(layers "B.Cu" "B.Mask" "B.Paste")
			(net "GND")
		)
	)
)
